(kicad_pcb
	(version 20260206)
	(generator "pcbnew")
	(generator_version "10.0")
	(general
		(thickness 1.6)
		(legacy_teardrops no)
	)
	(paper "A4")
	(title_block
		(title "01162023_DA0F0TEBIF0_F0T_Expander_BD_F_brd_V02_OCP.brd")
		(comment 1 "Grand Teton / footprints 4443-4449 of 9728")
	)
	(layers
		(0 "F.Cu" signal "TOP")
		(4 "In1.Cu" signal "GND")
		(6 "In2.Cu" signal "VCC")
		(8 "In3.Cu" signal "VCC1")
		(10 "In4.Cu" signal "GND1")
		(12 "In5.Cu" signal "IN1")
		(14 "In6.Cu" signal "GND2")
		(16 "In7.Cu" signal "IN2")
		(18 "In8.Cu" signal "GND3")
		(20 "In9.Cu" signal "IN3")
		(22 "In10.Cu" signal "GND4")
		(24 "In11.Cu" signal "IN4")
		(26 "In12.Cu" signal "GND5")
		(28 "In13.Cu" signal "IN5")
		(30 "In14.Cu" signal "GND6")
		(32 "In15.Cu" signal "IN6")
		(34 "In16.Cu" signal "GND7")
		(2 "B.Cu" signal "BOTTOM")
		(9 "F.Adhes" user "F.Adhesive")
		(11 "B.Adhes" user "B.Adhesive")
		(13 "F.Paste" user "Package Geometry/Pastemask Top")
		(15 "B.Paste" user "Package Geometry/Pastemask Bottom")
		(5 "F.SilkS" user "Ref Des/Silkscreen Top")
		(7 "B.SilkS" user "Ref Des/Silkscreen Bottom")
		(1 "F.Mask" user "Board Geometry/Soldermask Top")
		(3 "B.Mask" user "Board Geometry/Soldermask Bottom")
		(17 "Dwgs.User" user "User.Drawings")
		(19 "Cmts.User" user "User.Comments")
		(21 "Eco1.User" user "User.Eco1")
		(23 "Eco2.User" user "User.Eco2")
		(25 "Edge.Cuts" user "Board Geometry/Outline")
		(27 "Margin" user)
		(31 "F.CrtYd" user "Package Geometry/Place Bound Top")
		(29 "B.CrtYd" user "Package Geometry/Place Bound Bottom")
		(35 "F.Fab" user "Ref Des/Assembly Top")
		(33 "B.Fab" user "Ref Des/Assembly Bottom")
	)
	(footprint ""
		(layer "F.Cu")
		(at 452.864982 -114.833654 -90)
		(property "Reference" "PC832"
			(at 0 0 270)
			(layer "F.SilkS")
			(hide yes)
			(effects
				(font
					(size 1.27 1.27)
				)
			)
		)
		(property "Value" ""
			(at 0 0 270)
			(layer "F.Fab")
			(effects
				(font
					(size 1.27 1.27)
				)
			)
		)
		(duplicate_pad_numbers_are_jumpers no)
		(fp_line
			(start -1.2954 0.5842)
			(end -1.2954 -0.5842)
			(stroke
				(width 0.1524)
				(type default)
			)
			(layer "F.SilkS")
		)
		(fp_line
			(start 1.2954 0.5842)
			(end -1.2954 0.5842)
			(stroke
				(width 0.1524)
				(type default)
			)
			(layer "F.SilkS")
		)
		(fp_line
			(start -1.2954 -0.5842)
			(end 1.2954 -0.5842)
			(stroke
				(width 0.1524)
				(type default)
			)
			(layer "F.SilkS")
		)
		(fp_line
			(start 1.2954 -0.5842)
			(end 1.2954 0.5842)
			(stroke
				(width 0.1524)
				(type default)
			)
			(layer "F.SilkS")
		)
		(fp_line
			(start -0.8636 0.4572)
			(end -0.8636 0.4064)
			(stroke
				(width 0.1)
				(type default)
			)
			(layer "F.Fab")
		)
		(fp_line
			(start 0.8636 0.4572)
			(end -0.8636 0.4572)
			(stroke
				(width 0.1)
				(type default)
			)
			(layer "F.Fab")
		)
		(fp_line
			(start -1.1938 0.4064)
			(end -1.1938 -0.4064)
			(stroke
				(width 0.1)
				(type default)
			)
			(layer "F.Fab")
		)
		(fp_line
			(start -0.8636 0.4064)
			(end -1.1938 0.4064)
			(stroke
				(width 0.1)
				(type default)
			)
			(layer "F.Fab")
		)
		(fp_line
			(start 0.8636 0.4064)
			(end 0.8636 0.4572)
			(stroke
				(width 0.1)
				(type default)
			)
			(layer "F.Fab")
		)
		(fp_line
			(start 1.1938 0.4064)
			(end 0.8636 0.4064)
			(stroke
				(width 0.1)
				(type default)
			)
			(layer "F.Fab")
		)
		(fp_line
			(start -1.1938 -0.4064)
			(end -0.8636 -0.4064)
			(stroke
				(width 0.1)
				(type default)
			)
			(layer "F.Fab")
		)
		(fp_line
			(start -0.8636 -0.4064)
			(end -0.8636 -0.4572)
			(stroke
				(width 0.1)
				(type default)
			)
			(layer "F.Fab")
		)
		(fp_line
			(start 0.8636 -0.4064)
			(end 1.1938 -0.4064)
			(stroke
				(width 0.1)
				(type default)
			)
			(layer "F.Fab")
		)
		(fp_line
			(start 1.1938 -0.4064)
			(end 1.1938 0.4064)
			(stroke
				(width 0.1)
				(type default)
			)
			(layer "F.Fab")
		)
		(fp_line
			(start -0.8636 -0.4572)
			(end 0.8636 -0.4572)
			(stroke
				(width 0.1)
				(type default)
			)
			(layer "F.Fab")
		)
		(fp_line
			(start 0.8636 -0.4572)
			(end 0.8636 -0.4064)
			(stroke
				(width 0.1)
				(type default)
			)
			(layer "F.Fab")
		)
		(pad "1" smd rect
			(at -0.7366 0 180)
			(size 0.7112 0.8128)
			(layers "F.Cu" "F.Mask" "F.Paste")
			(net "GND")
		)
		(pad "2" smd rect
			(at 0.7366 0 180)
			(size 0.7112 0.8128)
			(layers "F.Cu" "F.Mask" "F.Paste")
			(net "P12V_NIC7_CO_AVIN_PD")
		)
	)
	(footprint ""
		(layer "F.Cu")
		(at 91.055444 -96.811592 -90)
		(property "Reference" "R695"
			(at 0 0 270)
			(layer "F.SilkS")
			(hide yes)
			(effects
				(font
					(size 1.27 1.27)
				)
			)
		)
		(property "Value" ""
			(at 0 0 270)
			(layer "F.Fab")
			(effects
				(font
					(size 1.27 1.27)
				)
			)
		)
		(duplicate_pad_numbers_are_jumpers no)
		(fp_line
			(start -0.7874 0.4064)
			(end -0.7874 -0.4064)
			(stroke
				(width 0.1524)
				(type default)
			)
			(layer "F.SilkS")
		)
		(fp_line
			(start 0.7874 0.4064)
			(end -0.7874 0.4064)
			(stroke
				(width 0.1524)
				(type default)
			)
			(layer "F.SilkS")
		)
		(fp_line
			(start -0.7874 -0.4064)
			(end 0.7874 -0.4064)
			(stroke
				(width 0.1524)
				(type default)
			)
			(layer "F.SilkS")
		)
		(fp_line
			(start 0.7874 -0.4064)
			(end 0.7874 0.4064)
			(stroke
				(width 0.1524)
				(type default)
			)
			(layer "F.SilkS")
		)
		(fp_line
			(start -0.67945 0.3048)
			(end -0.67945 -0.305054)
			(stroke
				(width 0.1)
				(type default)
			)
			(layer "F.Fab")
		)
		(fp_line
			(start -0.12065 0.3048)
			(end -0.67945 0.3048)
			(stroke
				(width 0.1)
				(type default)
			)
			(layer "F.Fab")
		)
		(fp_line
			(start 0.120396 0.3048)
			(end 0.120396 0.2794)
			(stroke
				(width 0.1)
				(type default)
			)
			(layer "F.Fab")
		)
		(fp_line
			(start 0.67945 0.3048)
			(end 0.120396 0.3048)
			(stroke
				(width 0.1)
				(type default)
			)
			(layer "F.Fab")
		)
		(fp_line
			(start -0.12065 0.2794)
			(end -0.12065 0.3048)
			(stroke
				(width 0.1)
				(type default)
			)
			(layer "F.Fab")
		)
		(fp_line
			(start 0.120396 0.2794)
			(end -0.12065 0.2794)
			(stroke
				(width 0.1)
				(type default)
			)
			(layer "F.Fab")
		)
		(fp_line
			(start -0.12065 -0.2794)
			(end 0.12065 -0.2794)
			(stroke
				(width 0.1)
				(type default)
			)
			(layer "F.Fab")
		)
		(fp_line
			(start 0.12065 -0.2794)
			(end 0.12065 -0.3048)
			(stroke
				(width 0.1)
				(type default)
			)
			(layer "F.Fab")
		)
		(fp_line
			(start 0.12065 -0.3048)
			(end 0.67945 -0.3048)
			(stroke
				(width 0.1)
				(type default)
			)
			(layer "F.Fab")
		)
		(fp_line
			(start 0.67945 -0.3048)
			(end 0.67945 0.3048)
			(stroke
				(width 0.1)
				(type default)
			)
			(layer "F.Fab")
		)
		(fp_line
			(start -0.67945 -0.305054)
			(end -0.12065 -0.305054)
			(stroke
				(width 0.1)
				(type default)
			)
			(layer "F.Fab")
		)
		(fp_line
			(start -0.12065 -0.305054)
			(end -0.12065 -0.2794)
			(stroke
				(width 0.1)
				(type default)
			)
			(layer "F.Fab")
		)
		(pad "1" smd circle
			(at -0.40005 0 270)
			(size 0 0)
			(layers "F.Cu" "F.Mask" "F.Paste")
			(net "NIC1_ADC_ALERT_N")
		)
		(pad "2" smd circle
			(at 0.40005 0 270)
			(size 0 0)
			(layers "F.Cu" "F.Mask" "F.Paste")
			(net "NIC_ADC_ALERT_N")
		)
	)
	(footprint ""
		(layer "F.Cu")
		(at 361.188 -192.278 180)
		(property "Reference" "R4655"
			(at 0 0 180)
			(layer "F.SilkS")
			(hide yes)
			(effects
				(font
					(size 1.27 1.27)
				)
			)
		)
		(property "Value" ""
			(at 0 0 180)
			(layer "F.Fab")
			(effects
				(font
					(size 1.27 1.27)
				)
			)
		)
		(duplicate_pad_numbers_are_jumpers no)
		(fp_line
			(start 0.7874 0.4064)
			(end -0.7874 0.4064)
			(stroke
				(width 0.1524)
				(type default)
			)
			(layer "F.SilkS")
		)
		(fp_line
			(start 0.7874 -0.4064)
			(end 0.7874 0.4064)
			(stroke
				(width 0.1524)
				(type default)
			)
			(layer "F.SilkS")
		)
		(fp_line
			(start -0.7874 0.4064)
			(end -0.7874 -0.4064)
			(stroke
				(width 0.1524)
				(type default)
			)
			(layer "F.SilkS")
		)
		(fp_line
			(start -0.7874 -0.4064)
			(end 0.7874 -0.4064)
			(stroke
				(width 0.1524)
				(type default)
			)
			(layer "F.SilkS")
		)
		(fp_line
			(start 0.67945 0.3048)
			(end 0.120396 0.3048)
			(stroke
				(width 0.1)
				(type default)
			)
			(layer "F.Fab")
		)
		(fp_line
			(start 0.67945 -0.3048)
			(end 0.67945 0.3048)
			(stroke
				(width 0.1)
				(type default)
			)
			(layer "F.Fab")
		)
		(fp_line
			(start 0.12065 -0.2794)
			(end 0.12065 -0.3048)
			(stroke
				(width 0.1)
				(type default)
			)
			(layer "F.Fab")
		)
		(fp_line
			(start 0.12065 -0.3048)
			(end 0.67945 -0.3048)
			(stroke
				(width 0.1)
				(type default)
			)
			(layer "F.Fab")
		)
		(fp_line
			(start 0.120396 0.3048)
			(end 0.120396 0.2794)
			(stroke
				(width 0.1)
				(type default)
			)
			(layer "F.Fab")
		)
		(fp_line
			(start 0.120396 0.2794)
			(end -0.12065 0.2794)
			(stroke
				(width 0.1)
				(type default)
			)
			(layer "F.Fab")
		)
		(fp_line
			(start -0.12065 0.3048)
			(end -0.67945 0.3048)
			(stroke
				(width 0.1)
				(type default)
			)
			(layer "F.Fab")
		)
		(fp_line
			(start -0.12065 0.2794)
			(end -0.12065 0.3048)
			(stroke
				(width 0.1)
				(type default)
			)
			(layer "F.Fab")
		)
		(fp_line
			(start -0.12065 -0.2794)
			(end 0.12065 -0.2794)
			(stroke
				(width 0.1)
				(type default)
			)
			(layer "F.Fab")
		)
		(fp_line
			(start -0.12065 -0.305054)
			(end -0.12065 -0.2794)
			(stroke
				(width 0.1)
				(type default)
			)
			(layer "F.Fab")
		)
		(fp_line
			(start -0.67945 0.3048)
			(end -0.67945 -0.305054)
			(stroke
				(width 0.1)
				(type default)
			)
			(layer "F.Fab")
		)
		(fp_line
			(start -0.67945 -0.305054)
			(end -0.12065 -0.305054)
			(stroke
				(width 0.1)
				(type default)
			)
			(layer "F.Fab")
		)
		(pad "1" smd circle
			(at -0.40005 0 180)
			(size 0 0)
			(layers "F.Cu" "F.Mask" "F.Paste")
			(net "GND")
		)
		(pad "2" smd circle
			(at 0.40005 0 180)
			(size 0 0)
			(layers "F.Cu" "F.Mask" "F.Paste")
			(net "PCA9555_1_PEX0_A1")
		)
	)
	(footprint ""
		(layer "F.Cu")
		(at 310.783986 -29.222954 -90)
		(property "Reference" "PC959"
			(at 0 0 270)
			(layer "F.SilkS")
			(hide yes)
			(effects
				(font
					(size 1.27 1.27)
				)
			)
		)
		(property "Value" ""
			(at 0 0 270)
			(layer "F.Fab")
			(effects
				(font
					(size 1.27 1.27)
				)
			)
		)
		(duplicate_pad_numbers_are_jumpers no)
		(fp_line
			(start -0.7874 0.4064)
			(end -0.7874 -0.4064)
			(stroke
				(width 0.1524)
				(type default)
			)
			(layer "F.SilkS")
		)
		(fp_line
			(start 0.7874 0.4064)
			(end -0.7874 0.4064)
			(stroke
				(width 0.1524)
				(type default)
			)
			(layer "F.SilkS")
		)
		(fp_line
			(start -0.7874 -0.4064)
			(end 0.7874 -0.4064)
			(stroke
				(width 0.1524)
				(type default)
			)
			(layer "F.SilkS")
		)
		(fp_line
			(start 0.7874 -0.4064)
			(end 0.7874 0.4064)
			(stroke
				(width 0.1524)
				(type default)
			)
			(layer "F.SilkS")
		)
		(fp_line
			(start -0.67945 0.3048)
			(end -0.67945 -0.305054)
			(stroke
				(width 0.1)
				(type default)
			)
			(layer "F.Fab")
		)
		(fp_line
			(start -0.12065 0.3048)
			(end -0.67945 0.3048)
			(stroke
				(width 0.1)
				(type default)
			)
			(layer "F.Fab")
		)
		(fp_line
			(start 0.120396 0.3048)
			(end 0.120396 0.2794)
			(stroke
				(width 0.1)
				(type default)
			)
			(layer "F.Fab")
		)
		(fp_line
			(start 0.67945 0.3048)
			(end 0.120396 0.3048)
			(stroke
				(width 0.1)
				(type default)
			)
			(layer "F.Fab")
		)
		(fp_line
			(start -0.12065 0.2794)
			(end -0.12065 0.3048)
			(stroke
				(width 0.1)
				(type default)
			)
			(layer "F.Fab")
		)
		(fp_line
			(start 0.120396 0.2794)
			(end -0.12065 0.2794)
			(stroke
				(width 0.1)
				(type default)
			)
			(layer "F.Fab")
		)
		(fp_line
			(start -0.12065 -0.2794)
			(end 0.12065 -0.2794)
			(stroke
				(width 0.1)
				(type default)
			)
			(layer "F.Fab")
		)
		(fp_line
			(start 0.12065 -0.2794)
			(end 0.12065 -0.3048)
			(stroke
				(width 0.1)
				(type default)
			)
			(layer "F.Fab")
		)
		(fp_line
			(start 0.12065 -0.3048)
			(end 0.67945 -0.3048)
			(stroke
				(width 0.1)
				(type default)
			)
			(layer "F.Fab")
		)
		(fp_line
			(start 0.67945 -0.3048)
			(end 0.67945 0.3048)
			(stroke
				(width 0.1)
				(type default)
			)
			(layer "F.Fab")
		)
		(fp_line
			(start -0.67945 -0.305054)
			(end -0.12065 -0.305054)
			(stroke
				(width 0.1)
				(type default)
			)
			(layer "F.Fab")
		)
		(fp_line
			(start -0.12065 -0.305054)
			(end -0.12065 -0.2794)
			(stroke
				(width 0.1)
				(type default)
			)
			(layer "F.Fab")
		)
		(pad "1" smd circle
			(at -0.40005 0 270)
			(size 0 0)
			(layers "F.Cu" "F.Mask" "F.Paste")
			(net "P3V3_AUX")
		)
		(pad "2" smd circle
			(at 0.40005 0 270)
			(size 0 0)
			(layers "F.Cu" "F.Mask" "F.Paste")
			(net "GND")
		)
	)
	(footprint ""
		(layer "F.Cu")
		(at 28.04922 -280.994612 -90)
		(property "Reference" "C3036"
			(at 0 0 270)
			(layer "F.SilkS")
			(hide yes)
			(effects
				(font
					(size 1.27 1.27)
				)
			)
		)
		(property "Value" ""
			(at 0 0 270)
			(layer "F.Fab")
			(effects
				(font
					(size 1.27 1.27)
				)
			)
		)
		(duplicate_pad_numbers_are_jumpers no)
		(fp_line
			(start -0.299974 0.150114)
			(end -0.299974 -0.150114)
			(stroke
				(width 0.1)
				(type default)
			)
			(layer "F.Fab")
		)
		(fp_line
			(start 0.299974 0.150114)
			(end -0.299974 0.150114)
			(stroke
				(width 0.1)
				(type default)
			)
			(layer "F.Fab")
		)
		(fp_line
			(start -0.299974 -0.150114)
			(end 0.299974 -0.150114)
			(stroke
				(width 0.1)
				(type default)
			)
			(layer "F.Fab")
		)
		(fp_line
			(start 0.299974 -0.150114)
			(end 0.299974 0.150114)
			(stroke
				(width 0.1)
				(type default)
			)
			(layer "F.Fab")
		)
		(pad "1" smd rect
			(at -0.2667 0 270)
			(size 0.3048 0.381)
			(layers "F.Cu" "F.Mask" "F.Paste")
			(net "P1V8_PLL0_PEX0")
		)
		(pad "2" smd rect
			(at 0.2667 0 270)
			(size 0.3048 0.381)
			(layers "F.Cu" "F.Mask" "F.Paste")
			(net "GND")
		)
	)
	(footprint ""
		(layer "F.Cu")
		(at 233.1974 -231.394 90)
		(property "Reference" "R4523"
			(at 0 0 90)
			(layer "F.SilkS")
			(hide yes)
			(effects
				(font
					(size 1.27 1.27)
				)
			)
		)
		(property "Value" ""
			(at 0 0 90)
			(layer "F.Fab")
			(effects
				(font
					(size 1.27 1.27)
				)
			)
		)
		(duplicate_pad_numbers_are_jumpers no)
		(fp_line
			(start 0.7874 -0.4064)
			(end 0.7874 0.4064)
			(stroke
				(width 0.1524)
				(type default)
			)
			(layer "F.SilkS")
		)
		(fp_line
			(start -0.7874 -0.4064)
			(end 0.7874 -0.4064)
			(stroke
				(width 0.1524)
				(type default)
			)
			(layer "F.SilkS")
		)
		(fp_line
			(start 0.7874 0.4064)
			(end -0.7874 0.4064)
			(stroke
				(width 0.1524)
				(type default)
			)
			(layer "F.SilkS")
		)
		(fp_line
			(start -0.7874 0.4064)
			(end -0.7874 -0.4064)
			(stroke
				(width 0.1524)
				(type default)
			)
			(layer "F.SilkS")
		)
		(fp_line
			(start -0.12065 -0.305054)
			(end -0.12065 -0.2794)
			(stroke
				(width 0.1)
				(type default)
			)
			(layer "F.Fab")
		)
		(fp_line
			(start -0.67945 -0.305054)
			(end -0.12065 -0.305054)
			(stroke
				(width 0.1)
				(type default)
			)
			(layer "F.Fab")
		)
		(fp_line
			(start 0.67945 -0.3048)
			(end 0.67945 0.3048)
			(stroke
				(width 0.1)
				(type default)
			)
			(layer "F.Fab")
		)
		(fp_line
			(start 0.12065 -0.3048)
			(end 0.67945 -0.3048)
			(stroke
				(width 0.1)
				(type default)
			)
			(layer "F.Fab")
		)
		(fp_line
			(start 0.12065 -0.2794)
			(end 0.12065 -0.3048)
			(stroke
				(width 0.1)
				(type default)
			)
			(layer "F.Fab")
		)
		(fp_line
			(start -0.12065 -0.2794)
			(end 0.12065 -0.2794)
			(stroke
				(width 0.1)
				(type default)
			)
			(layer "F.Fab")
		)
		(fp_line
			(start 0.120396 0.2794)
			(end -0.12065 0.2794)
			(stroke
				(width 0.1)
				(type default)
			)
			(layer "F.Fab")
		)
		(fp_line
			(start -0.12065 0.2794)
			(end -0.12065 0.3048)
			(stroke
				(width 0.1)
				(type default)
			)
			(layer "F.Fab")
		)
		(fp_line
			(start 0.67945 0.3048)
			(end 0.120396 0.3048)
			(stroke
				(width 0.1)
				(type default)
			)
			(layer "F.Fab")
		)
		(fp_line
			(start 0.120396 0.3048)
			(end 0.120396 0.2794)
			(stroke
				(width 0.1)
				(type default)
			)
			(layer "F.Fab")
		)
		(fp_line
			(start -0.12065 0.3048)
			(end -0.67945 0.3048)
			(stroke
				(width 0.1)
				(type default)
			)
			(layer "F.Fab")
		)
		(fp_line
			(start -0.67945 0.3048)
			(end -0.67945 -0.305054)
			(stroke
				(width 0.1)
				(type default)
			)
			(layer "F.Fab")
		)
		(pad "1" smd circle
			(at -0.40005 0 90)
			(size 0 0)
			(layers "F.Cu" "F.Mask" "F.Paste")
			(net "SSD9_PWRDIS_BIC")
		)
		(pad "2" smd circle
			(at 0.40005 0 90)
			(size 0 0)
			(layers "F.Cu" "F.Mask" "F.Paste")
			(net "SSD9_PWRDIS_BIC_R")
		)
	)
	(footprint ""
		(layer "F.Cu")
		(at 137.35558 -152.71115 90)
		(property "Reference" "R707"
			(at 0 0 90)
			(layer "F.SilkS")
			(hide yes)
			(effects
				(font
					(size 1.27 1.27)
				)
			)
		)
		(property "Value" ""
			(at 0 0 90)
			(layer "F.Fab")
			(effects
				(font
					(size 1.27 1.27)
				)
			)
		)
		(duplicate_pad_numbers_are_jumpers no)
		(fp_line
			(start 0.7874 -0.4064)
			(end 0.7874 0.4064)
			(stroke
				(width 0.1524)
				(type default)
			)
			(layer "F.SilkS")
		)
		(fp_line
			(start -0.7874 -0.4064)
			(end 0.7874 -0.4064)
			(stroke
				(width 0.1524)
				(type default)
			)
			(layer "F.SilkS")
		)
		(fp_line
			(start 0.7874 0.4064)
			(end -0.7874 0.4064)
			(stroke
				(width 0.1524)
				(type default)
			)
			(layer "F.SilkS")
		)
		(fp_line
			(start -0.7874 0.4064)
			(end -0.7874 -0.4064)
			(stroke
				(width 0.1524)
				(type default)
			)
			(layer "F.SilkS")
		)
		(fp_line
			(start -0.12065 -0.305054)
			(end -0.12065 -0.2794)
			(stroke
				(width 0.1)
				(type default)
			)
			(layer "F.Fab")
		)
		(fp_line
			(start -0.67945 -0.305054)
			(end -0.12065 -0.305054)
			(stroke
				(width 0.1)
				(type default)
			)
			(layer "F.Fab")
		)
		(fp_line
			(start 0.67945 -0.3048)
			(end 0.67945 0.3048)
			(stroke
				(width 0.1)
				(type default)
			)
			(layer "F.Fab")
		)
		(fp_line
			(start 0.12065 -0.3048)
			(end 0.67945 -0.3048)
			(stroke
				(width 0.1)
				(type default)
			)
			(layer "F.Fab")
		)
		(fp_line
			(start 0.12065 -0.2794)
			(end 0.12065 -0.3048)
			(stroke
				(width 0.1)
				(type default)
			)
			(layer "F.Fab")
		)
		(fp_line
			(start -0.12065 -0.2794)
			(end 0.12065 -0.2794)
			(stroke
				(width 0.1)
				(type default)
			)
			(layer "F.Fab")
		)
		(fp_line
			(start 0.120396 0.2794)
			(end -0.12065 0.2794)
			(stroke
				(width 0.1)
				(type default)
			)
			(layer "F.Fab")
		)
		(fp_line
			(start -0.12065 0.2794)
			(end -0.12065 0.3048)
			(stroke
				(width 0.1)
				(type default)
			)
			(layer "F.Fab")
		)
		(fp_line
			(start 0.67945 0.3048)
			(end 0.120396 0.3048)
			(stroke
				(width 0.1)
				(type default)
			)
			(layer "F.Fab")
		)
		(fp_line
			(start 0.120396 0.3048)
			(end 0.120396 0.2794)
			(stroke
				(width 0.1)
				(type default)
			)
			(layer "F.Fab")
		)
		(fp_line
			(start -0.12065 0.3048)
			(end -0.67945 0.3048)
			(stroke
				(width 0.1)
				(type default)
			)
			(layer "F.Fab")
		)
		(fp_line
			(start -0.67945 0.3048)
			(end -0.67945 -0.305054)
			(stroke
				(width 0.1)
				(type default)
			)
			(layer "F.Fab")
		)
		(pad "1" smd circle
			(at -0.40005 0 90)
			(size 0 0)
			(layers "F.Cu" "F.Mask" "F.Paste")
			(net "NIC2_ADC_A1")
		)
		(pad "2" smd circle
			(at 0.40005 0 90)
			(size 0 0)
			(layers "F.Cu" "F.Mask" "F.Paste")
			(net "GND")
		)
	)
)
